(kicad_pcb
	(version 20241229)
	(generator "pcbnew")
	(generator_version "9.0")
	(general
		(thickness 1.711)
		(legacy_teardrops no)
	)
	(paper "A4")
	(title_block
		(title "Antmicro Baseboard for Jetson AGX Thor")
		(date "2026-02-18")
		(rev "1.1.0")
		(company "Antmicro Ltd")
		(comment 1 "www.antmicro.com")
		(comment 9 "footprints 297-301 of 1170")
	)
	(layers
		(0 "F.Cu" signal)
		(4 "In1.Cu" signal)
		(6 "In2.Cu" signal)
		(8 "In3.Cu" signal)
		(10 "In4.Cu" jumper)
		(12 "In5.Cu" signal)
		(14 "In6.Cu" signal)
		(16 "In7.Cu" signal)
		(18 "In8.Cu" signal)
		(2 "B.Cu" signal)
		(9 "F.Adhes" user "F.Adhesive")
		(11 "B.Adhes" user "B.Adhesive")
		(13 "F.Paste" user)
		(15 "B.Paste" user)
		(5 "F.SilkS" user "F.Silkscreen")
		(7 "B.SilkS" user "B.Silkscreen")
		(1 "F.Mask" user)
		(3 "B.Mask" user)
		(17 "Dwgs.User" user "User.Drawings")
		(19 "Cmts.User" user "User.Comments")
		(21 "Eco1.User" user "User.Eco1")
		(23 "Eco2.User" user "User.Eco2")
		(25 "Edge.Cuts" user)
		(27 "Margin" user)
		(31 "F.CrtYd" user "F.Courtyard")
		(29 "B.CrtYd" user "B.Courtyard")
		(35 "F.Fab" user)
		(33 "B.Fab" user)
	)
	(footprint "antmicro-footprints:R_0402_1005Metric"
		(layer "F.Cu")
		(at 83.5 55.5)
		(descr "Resistor SMD 0402")
		(tags "resistor SMD 0402")
		(property "Reference" "R287"
			(at -1.5 -0.6 0)
			(layer "F.SilkS")
			(effects
				(font
					(size 0.7 0.7)
					(thickness 0.15)
				)
				(justify left bottom)
			)
		)
		(property "Value" "R_10k_0402"
			(at -1.011843 1.772047 0)
			(layer "F.Fab")
			(effects
				(font
					(size 0.7 0.7)
					(thickness 0.15)
				)
				(justify left bottom)
			)
		)
		(property "Datasheet" "https://www.bourns.com/docs/product-datasheets/cr.pdf"
			(at 0 0 0)
			(layer "F.Fab")
			(hide yes)
			(effects
				(font
					(size 1.27 1.27)
					(thickness 0.15)
				)
			)
		)
		(property "Description" "SMD Chip Resistor, 10 kohm, ± 1%, 62.5 mW, 0402 [1005 Metric], Thick Film, General Purpose"
			(at 0 0 0)
			(layer "F.Fab")
			(hide yes)
			(effects
				(font
					(size 1.27 1.27)
					(thickness 0.15)
				)
			)
		)
		(property "MPN" "CR0402-FX-1002GLF"
			(at 0 0 0)
			(unlocked yes)
			(layer "F.Fab")
			(hide yes)
			(effects
				(font
					(size 1 1)
					(thickness 0.15)
				)
			)
		)
		(property "Manufacturer" "Bourns"
			(at 0 0 0)
			(unlocked yes)
			(layer "F.Fab")
			(hide yes)
			(effects
				(font
					(size 1 1)
					(thickness 0.15)
				)
			)
		)
		(property "License" "Apache-2.0"
			(at 0 0 0)
			(unlocked yes)
			(layer "F.Fab")
			(hide yes)
			(effects
				(font
					(size 1 1)
					(thickness 0.15)
				)
			)
		)
		(property "Author" "Antmicro"
			(at 0 0 0)
			(unlocked yes)
			(layer "F.Fab")
			(hide yes)
			(effects
				(font
					(size 1 1)
					(thickness 0.15)
				)
			)
		)
		(property "Val" "10k"
			(at 0 0 0)
			(unlocked yes)
			(layer "F.Fab")
			(hide yes)
			(effects
				(font
					(size 1 1)
					(thickness 0.15)
				)
			)
		)
		(property "Tolerance" "1%"
			(at 0 0 0)
			(unlocked yes)
			(layer "F.Fab")
			(hide yes)
			(effects
				(font
					(size 1 1)
					(thickness 0.15)
				)
			)
		)
		(sheetname "/SoM_Power/")
		(sheetfile "som_power.kicad_sch")
		(attr smd)
		(fp_rect
			(start -0.925 -0.47)
			(end 0.925 0.47)
			(stroke
				(width 0.05)
				(type default)
			)
			(fill no)
			(layer "F.CrtYd")
		)
		(fp_rect
			(start -0.5 -0.25)
			(end 0.5 0.25)
			(stroke
				(width 0.15)
				(type solid)
			)
			(fill no)
			(layer "F.Fab")
		)
		(fp_text user "License: Apache-2.0"
			(at -0.95 5.169 0)
			(layer "F.Fab")
			(effects
				(font
					(size 0.7 0.7)
					(thickness 0.15)
				)
				(justify left bottom)
			)
		)
		(fp_text user "${REFERENCE}"
			(at -0.95 3.168 0)
			(layer "F.Fab")
			(effects
				(font
					(size 0.7 0.7)
					(thickness 0.15)
				)
				(justify left bottom)
			)
		)
		(fp_text user "Author: Antmicro"
			(at -0.95 4.169 0)
			(layer "F.Fab")
			(effects
				(font
					(size 0.7 0.7)
					(thickness 0.15)
				)
				(justify left bottom)
			)
		)
		(pad "1" smd roundrect
			(at -0.48 0)
			(size 0.59 0.64)
			(layers "F.Cu" "F.Mask" "F.Paste")
			(roundrect_rratio 0.25)
			(net 683 "/SoM_Power/~{SOM_PRSNT}")
			(pintype "passive")
		)
		(pad "2" smd roundrect
			(at 0.48 0)
			(size 0.59 0.64)
			(layers "F.Cu" "F.Mask" "F.Paste")
			(roundrect_rratio 0.25)
			(net 491 "+5V_AON")
			(pintype "passive")
		)
	)
	(footprint "antmicro-footprints:R_0402_1005Metric"
		(layer "F.Cu")
		(at 138.7 111.72 -90)
		(descr "Resistor SMD 0402")
		(tags "resistor SMD 0402")
		(property "Reference" "R403"
			(at 0.78 0.4 90)
			(layer "F.SilkS")
			(effects
				(font
					(size 0.7 0.7)
					(thickness 0.15)
				)
				(justify right top)
			)
		)
		(property "Value" "R_0R_0402"
			(at -1.011843 1.772047 90)
			(layer "F.Fab")
			(effects
				(font
					(size 0.7 0.7)
					(thickness 0.15)
				)
				(justify right top)
			)
		)
		(property "Datasheet" "https://industrial.panasonic.com/cdbs/www-data/pdf/RDA0000/AOA0000C301.pdf"
			(at 0 0 90)
			(layer "F.Fab")
			(hide yes)
			(effects
				(font
					(size 1.27 1.27)
					(thickness 0.15)
				)
			)
		)
		(property "Description" "SMD Chip Resistor, Jumper, 0 ohm, 100 mW, 0402 [1005 Metric], Thick Film, General Purpose"
			(at 0 0 90)
			(layer "F.Fab")
			(hide yes)
			(effects
				(font
					(size 1.27 1.27)
					(thickness 0.15)
				)
			)
		)
		(property "MPN" "ERJ2GE0R00X"
			(at 0 0 270)
			(unlocked yes)
			(layer "F.Fab")
			(hide yes)
			(effects
				(font
					(size 1 1)
					(thickness 0.15)
				)
			)
		)
		(property "Manufacturer" "Panasonic"
			(at 0 0 270)
			(unlocked yes)
			(layer "F.Fab")
			(hide yes)
			(effects
				(font
					(size 1 1)
					(thickness 0.15)
				)
			)
		)
		(property "License" "Apache-2.0"
			(at 0 0 270)
			(unlocked yes)
			(layer "F.Fab")
			(hide yes)
			(effects
				(font
					(size 1 1)
					(thickness 0.15)
				)
			)
		)
		(property "Author" "Antmicro"
			(at 0 0 270)
			(unlocked yes)
			(layer "F.Fab")
			(hide yes)
			(effects
				(font
					(size 1 1)
					(thickness 0.15)
				)
			)
		)
		(property "Val" "0R"
			(at 0 0 270)
			(unlocked yes)
			(layer "F.Fab")
			(hide yes)
			(effects
				(font
					(size 1 1)
					(thickness 0.15)
				)
			)
		)
		(property "Tolerance" "~"
			(at 0 0 270)
			(unlocked yes)
			(layer "F.Fab")
			(hide yes)
			(effects
				(font
					(size 1 1)
					(thickness 0.15)
				)
			)
		)
		(property "Current" "1A"
			(at 0 0 270)
			(unlocked yes)
			(layer "F.Fab")
			(hide yes)
			(effects
				(font
					(size 1 1)
					(thickness 0.15)
				)
			)
		)
		(sheetname "/Peripherals/")
		(sheetfile "peripherals.kicad_sch")
		(attr smd)
		(fp_rect
			(start -0.925 -0.47)
			(end 0.925 0.47)
			(stroke
				(width 0.05)
				(type default)
			)
			(fill no)
			(layer "F.CrtYd")
		)
		(fp_rect
			(start -0.5 -0.25)
			(end 0.5 0.25)
			(stroke
				(width 0.15)
				(type solid)
			)
			(fill no)
			(layer "F.Fab")
		)
		(fp_text user "${REFERENCE}"
			(at -0.95 3.168 90)
			(layer "F.Fab")
			(effects
				(font
					(size 0.7 0.7)
					(thickness 0.15)
				)
				(justify right top)
			)
		)
		(fp_text user "Author: Antmicro"
			(at -0.95 4.169 90)
			(layer "F.Fab")
			(effects
				(font
					(size 0.7 0.7)
					(thickness 0.15)
				)
				(justify right top)
			)
		)
		(fp_text user "License: Apache-2.0"
			(at -0.95 5.169 90)
			(layer "F.Fab")
			(effects
				(font
					(size 0.7 0.7)
					(thickness 0.15)
				)
				(justify right top)
			)
		)
		(pad "1" smd roundrect
			(at -0.48 0 270)
			(size 0.59 0.64)
			(layers "F.Cu" "F.Mask" "F.Paste")
			(roundrect_rratio 0.25)
			(net 1316 "/Peripherals/GPIOEX_P0_4")
			(pintype "passive")
		)
		(pad "2" smd roundrect
			(at 0.48 0 270)
			(size 0.59 0.64)
			(layers "F.Cu" "F.Mask" "F.Paste")
			(roundrect_rratio 0.25)
			(net 1100 "/Peripherals/TPM_RST")
			(pintype "passive")
		)
	)
	(footprint "antmicro-footprints:TP_SMD_0.75mm"
		(layer "F.Cu")
		(at 142.9 112.2)
		(property "Reference" "TP71"
			(at 0.5 2.9 90)
			(layer "F.SilkS")
			(effects
				(font
					(size 0.7 0.7)
					(thickness 0.15)
				)
				(justify left bottom)
			)
		)
		(property "Value" "TP_0.75mm_SMD"
			(at 0 1.2 0)
			(layer "F.Fab")
			(effects
				(font
					(size 0.7 0.7)
					(thickness 0.15)
				)
				(justify left bottom)
			)
		)
		(property "Description" "SMT test point"
			(at 0 0 0)
			(layer "F.Fab")
			(hide yes)
			(effects
				(font
					(size 1.27 1.27)
					(thickness 0.15)
				)
			)
		)
		(property "MPN" ""
			(at 0 0 0)
			(unlocked yes)
			(layer "F.Fab")
			(hide yes)
			(effects
				(font
					(size 1 1)
					(thickness 0.15)
				)
			)
		)
		(property "Manufacturer" ""
			(at 0 0 0)
			(unlocked yes)
			(layer "F.Fab")
			(hide yes)
			(effects
				(font
					(size 1 1)
					(thickness 0.15)
				)
			)
		)
		(property "Author" "Antmicro"
			(at 0 0 0)
			(unlocked yes)
			(layer "F.Fab")
			(hide yes)
			(effects
				(font
					(size 1 1)
					(thickness 0.15)
				)
			)
		)
		(property "License" "Apache-2.0"
			(at 0 0 0)
			(unlocked yes)
			(layer "F.Fab")
			(hide yes)
			(effects
				(font
					(size 1 1)
					(thickness 0.15)
				)
			)
		)
		(sheetname "/Peripherals/")
		(sheetfile "peripherals.kicad_sch")
		(attr exclude_from_pos_files exclude_from_bom)
		(fp_circle
			(center 0 0)
			(end 0.475 0)
			(stroke
				(width 0.05)
				(type default)
			)
			(fill no)
			(layer "F.CrtYd")
		)
		(fp_text user "${REFERENCE}"
			(at -0.4 2.7 0)
			(layer "F.Fab")
			(effects
				(font
					(size 0.7 0.7)
					(thickness 0.15)
				)
				(justify left bottom)
			)
		)
		(fp_text user "License: Apache-2.0"
			(at -0.4 5.101 0)
			(layer "F.Fab")
			(effects
				(font
					(size 0.7 0.7)
					(thickness 0.15)
				)
				(justify left bottom)
			)
		)
		(fp_text user "Author: Antmicro"
			(at -0.4 3.901 0)
			(layer "F.Fab")
			(effects
				(font
					(size 0.7 0.7)
					(thickness 0.15)
				)
				(justify left bottom)
			)
		)
		(pad "1" smd circle
			(at 0 0)
			(size 0.75 0.75)
			(layers "F.Cu" "F.Mask")
			(net 1378 "Net-(R406-Pad2)")
			(pinfunction "1")
			(pintype "passive")
		)
	)
	(footprint "antmicro-footprints:C_0402_1005Metric"
		(layer "F.Cu")
		(at 81.1 75.8 -90)
		(descr "Capacitor SMD 0402")
		(tags "capacitor SMD 0402")
		(property "Reference" "C342"
			(at 0.9 0.4 90)
			(layer "F.SilkS")
			(effects
				(font
					(size 0.7 0.7)
					(thickness 0.15)
				)
				(justify right top)
			)
		)
		(property "Value" "C_100n_0402"
			(at -1.022927 2.155213 90)
			(layer "F.Fab")
			(effects
				(font
					(size 0.7 0.7)
					(thickness 0.15)
				)
				(justify right top)
			)
		)
		(property "Datasheet" "https://www.murata.com/products/productdetail?partno=GRM155R61H104KE14%23"
			(at 0 0 90)
			(layer "F.Fab")
			(hide yes)
			(effects
				(font
					(size 1.27 1.27)
					(thickness 0.15)
				)
			)
		)
		(property "Description" "SMD Multilayer Ceramic Capacitor, 0.1 µF, 50 V, 0402 [1005 Metric], ± 10%, X5R, GRM Series"
			(at 0 0 90)
			(layer "F.Fab")
			(hide yes)
			(effects
				(font
					(size 1.27 1.27)
					(thickness 0.15)
				)
			)
		)
		(property "Manufacturer" "Murata"
			(at 0 0 270)
			(unlocked yes)
			(layer "F.Fab")
			(hide yes)
			(effects
				(font
					(size 1 1)
					(thickness 0.15)
				)
			)
		)
		(property "MPN" "GRM155R61H104KE14D"
			(at 0 0 270)
			(unlocked yes)
			(layer "F.Fab")
			(hide yes)
			(effects
				(font
					(size 1 1)
					(thickness 0.15)
				)
			)
		)
		(property "Val" "100n"
			(at 0 0 270)
			(unlocked yes)
			(layer "F.Fab")
			(hide yes)
			(effects
				(font
					(size 1 1)
					(thickness 0.15)
				)
			)
		)
		(property "License" "Apache-2.0"
			(at 0 0 270)
			(unlocked yes)
			(layer "F.Fab")
			(hide yes)
			(effects
				(font
					(size 1 1)
					(thickness 0.15)
				)
			)
		)
		(property "Author" "Antmicro"
			(at 0 0 270)
			(unlocked yes)
			(layer "F.Fab")
			(hide yes)
			(effects
				(font
					(size 1 1)
					(thickness 0.15)
				)
			)
		)
		(property "Voltage" "50V"
			(at 0 0 270)
			(unlocked yes)
			(layer "F.Fab")
			(hide yes)
			(effects
				(font
					(size 1 1)
					(thickness 0.15)
				)
			)
		)
		(property "Dielectric" "X5R"
			(at 0 0 270)
			(unlocked yes)
			(layer "F.Fab")
			(hide yes)
			(effects
				(font
					(size 1 1)
					(thickness 0.15)
				)
			)
		)
		(sheetname "/SoM_IO2/")
		(sheetfile "som_io2.kicad_sch")
		(attr smd)
		(fp_poly
			(pts
				(xy -0.925 -0.47) (xy 0.925 -0.47) (xy 0.925 0.47) (xy -0.925 0.47)
			)
			(stroke
				(width 0.05)
				(type default)
			)
			(fill no)
			(layer "F.CrtYd")
		)
		(fp_line
			(start -0.494 0.248)
			(end -0.494 -0.25)
			(stroke
				(width 0.15)
				(type solid)
			)
			(layer "F.Fab")
		)
		(fp_line
			(start 0.504 0.248)
			(end -0.494 0.248)
			(stroke
				(width 0.15)
				(type solid)
			)
			(layer "F.Fab")
		)
		(fp_line
			(start -0.494 -0.25)
			(end 0.504 -0.25)
			(stroke
				(width 0.15)
				(type solid)
			)
			(layer "F.Fab")
		)
		(fp_line
			(start 0.504 -0.25)
			(end 0.504 0.248)
			(stroke
				(width 0.15)
				(type solid)
			)
			(layer "F.Fab")
		)
		(fp_text user "${REFERENCE}"
			(at -0.939 4.599 90)
			(layer "F.Fab")
			(effects
				(font
					(size 0.7 0.7)
					(thickness 0.15)
				)
				(justify right top)
			)
		)
		(fp_text user "License: Apache-2.0"
			(at -0.939 5.799 90)
			(layer "F.Fab")
			(effects
				(font
					(size 0.7 0.7)
					(thickness 0.15)
				)
				(justify right top)
			)
		)
		(fp_text user "Author: Antmicro"
			(at -0.939 3.399 90)
			(layer "F.Fab")
			(effects
				(font
					(size 0.7 0.7)
					(thickness 0.15)
				)
				(justify right top)
			)
		)
		(pad "1" smd roundrect
			(at -0.48 0 270)
			(size 0.59 0.64)
			(layers "F.Cu" "F.Mask" "F.Paste")
			(roundrect_rratio 0.25)
			(net 1262 "/SoM_IO2/DP2.AUX_C+")
			(pintype "passive")
		)
		(pad "2" smd roundrect
			(at 0.48 0 270)
			(size 0.59 0.64)
			(layers "F.Cu" "F.Mask" "F.Paste")
			(roundrect_rratio 0.25)
			(net 572 "/Expansion connector/DP2.AUX+")
			(pintype "passive")
		)
	)
	(footprint "antmicro-footprints:LED_0603_1608Metric_G"
		(layer "F.Cu")
		(at 235.540532 121.71 180)
		(descr "LED SMD 0603 Green")
		(tags "LED SMD 0603 Green")
		(property "Reference" "D47"
			(at -1.059468 -0.799999 0)
			(layer "F.SilkS")
			(effects
				(font
					(size 0.7 0.7)
					(thickness 0.15)
				)
				(justify right top)
			)
		)
		(property "Value" "LED_G_0603_LTST-C190GKT"
			(at -0.001 1.599 0)
			(layer "F.Fab")
			(effects
				(font
					(size 0.7 0.7)
					(thickness 0.15)
				)
				(justify right top)
			)
		)
		(property "Datasheet" "https://media.digikey.com/pdf/Data%20Sheets/Lite-On%20PDFs/LTST-C190GKT.pdf"
			(at 0 0 0)
			(layer "F.Fab")
			(hide yes)
			(effects
				(font
					(size 1.27 1.27)
					(thickness 0.15)
				)
			)
		)
		(property "Description" "LED, Green, SMD, 0603, 20 mA, 2.1 V, 569 nm"
			(at 0 0 0)
			(layer "F.Fab")
			(hide yes)
			(effects
				(font
					(size 1.27 1.27)
					(thickness 0.15)
				)
			)
		)
		(property "MPN" "LTST-C190GKT"
			(at 0 0 180)
			(unlocked yes)
			(layer "F.Fab")
			(hide yes)
			(effects
				(font
					(size 1 1)
					(thickness 0.15)
				)
			)
		)
		(property "Manufacturer" "Lite-On"
			(at 0 0 180)
			(unlocked yes)
			(layer "F.Fab")
			(hide yes)
			(effects
				(font
					(size 1 1)
					(thickness 0.15)
				)
			)
		)
		(property "Author" "Antmicro"
			(at 0 0 180)
			(unlocked yes)
			(layer "F.Fab")
			(hide yes)
			(effects
				(font
					(size 1 1)
					(thickness 0.15)
				)
			)
		)
		(property "License" "Apache-2.0"
			(at 0 0 180)
			(unlocked yes)
			(layer "F.Fab")
			(hide yes)
			(effects
				(font
					(size 1 1)
					(thickness 0.15)
				)
			)
		)
		(property "Color" "Green"
			(at 0 0 180)
			(unlocked yes)
			(layer "F.Fab")
			(hide yes)
			(effects
				(font
					(size 1 1)
					(thickness 0.15)
				)
			)
		)
		(sheetname "/USB Hub/")
		(sheetfile "usb_hub.kicad_sch")
		(attr smd)
		(fp_line
			(start 0.22 0.35)
			(end -0.22 0.35)
			(stroke
				(width 0.15)
				(type solid)
			)
			(layer "F.SilkS")
		)
		(fp_line
			(start 0.22 -0.35)
			(end -0.22 -0.35)
			(stroke
				(width 0.15)
				(type solid)
			)
			(layer "F.SilkS")
		)
		(fp_line
			(start 0.105328 0.201008)
			(end 0.105329 -0.198992)
			(stroke
				(width 0.1)
				(type solid)
			)
			(layer "F.SilkS")
		)
		(fp_line
			(start 0.105328 0.201008)
			(end -0.094672 0.001008)
			(stroke
				(width 0.1)
				(type solid)
			)
			(layer "F.SilkS")
		)
		(fp_line
			(start 0.105328 0.001008)
			(end 0.240001 0.001)
			(stroke
				(width 0.1)
				(type solid)
			)
			(layer "F.SilkS")
		)
		(fp_line
			(start -0.094672 0.201008)
			(end -0.094672 -0.198992)
			(stroke
				(width 0.1)
				(type solid)
			)
			(layer "F.SilkS")
		)
		(fp_line
			(start -0.094672 0.001008)
			(end 0.105329 -0.198992)
			(stroke
				(width 0.1)
				(type solid)
			)
			(layer "F.SilkS")
		)
		(fp_line
			(start -0.094672 0.001008)
			(end -0.24 0.001008)
			(stroke
				(width 0.1)
				(type solid)
			)
			(layer "F.SilkS")
		)
		(fp_line
			(start -1.18 -0.319)
			(end -1.18 0.321)
			(stroke
				(width 0.15)
				(type solid)
			)
			(layer "F.SilkS")
		)
		(fp_poly
			(pts
				(xy 1.25 0.65) (xy -1.25 0.65) (xy -1.25 -0.65) (xy 1.25 -0.65)
			)
			(stroke
				(width 0.05)
				(type solid)
			)
			(fill no)
			(layer "F.CrtYd")
		)
		(fp_line
			(start 0.599 0)
			(end 0.200999 0)
			(stroke
				(width 0.15)
				(type solid)
			)
			(layer "F.Fab")
		)
		(fp_line
			(start 0.201 0.2)
			(end 0.200999 0)
			(stroke
				(width 0.15)
				(type solid)
			)
			(layer "F.Fab")
		)
		(fp_line
			(start 0.201 -0.202)
			(end -0.101 0)
			(stroke
				(width 0.15)
				(type solid)
			)
			(layer "F.Fab")
		)
		(fp_line
			(start 0.200999 0)
			(end 0.201 -0.202)
			(stroke
				(width 0.15)
				(type solid)
			)
			(layer "F.Fab")
		)
		(fp_line
			(start -0.101 0)
			(end 0.201 0.2)
			(stroke
				(width 0.15)
				(type solid)
			)
			(layer "F.Fab")
		)
		(fp_line
			(start -0.199 0.2)
			(end -0.199 0.1)
			(stroke
				(width 0.15)
				(type solid)
			)
			(layer "F.Fab")
		)
		(fp_line
			(start -0.199 0)
			(end -0.597 0)
			(stroke
				(width 0.15)
				(type solid)
			)
			(layer "F.Fab")
		)
		(fp_line
			(start -0.199 -0.202)
			(end -0.199 0.1)
			(stroke
				(width 0.15)
				(type solid)
			)
			(layer "F.Fab")
		)
		(fp_poly
			(pts
				(xy 0.848 0.4) (xy -0.85 0.4) (xy -0.85 -0.402) (xy 0.848 -0.401999)
			)
			(stroke
				(width 0.15)
				(type solid)
			)
			(fill no)
			(layer "F.Fab")
		)
		(fp_text user "License: Apache-2.0"
			(at -1.4224 3.599 0)
			(layer "F.Fab")
			(effects
				(font
					(size 0.7 0.7)
					(thickness 0.15)
				)
				(justify right top)
			)
		)
		(fp_text user "${REFERENCE}"
			(at -1.4224 5.999 0)
			(layer "F.Fab")
			(effects
				(font
					(size 0.7 0.7)
					(thickness 0.15)
				)
				(justify right top)
			)
		)
		(fp_text user "Author: Antmicro"
			(at -1.4224 4.799 0)
			(layer "F.Fab")
			(effects
				(font
					(size 0.7 0.7)
					(thickness 0.15)
				)
				(justify right top)
			)
		)
		(pad "1" smd roundrect
			(at -0.7 0)
			(size 0.8 1)
			(layers "F.Cu" "F.Mask" "F.Paste")
			(roundrect_rratio 0.2)
			(net 1 "GND")
			(pinfunction "C")
			(pintype "passive")
		)
		(pad "2" smd roundrect
			(at 0.7 0)
			(size 0.8 1)
			(layers "F.Cu" "F.Mask" "F.Paste")
			(roundrect_rratio 0.2)
			(net 1389 "Net-(D47-A)")
			(pinfunction "A")
			(pintype "passive")
		)
	)
)
